(kicad_pcb
	(version 20260206)
	(generator "pcbnew")
	(generator_version "10.0")
	(general
		(thickness 1.6)
		(legacy_teardrops no)
	)
	(paper "A4")
	(title_block
		(title "Bryce Canyon_R.DPB_16317-1_OCP.brd")
		(comment 1 "Bryce Canyon / footprints 1746-1748 of 2099")
	)
	(layers
		(0 "F.Cu" signal "TOP")
		(4 "In1.Cu" signal "L2GND")
		(6 "In2.Cu" signal "L3")
		(8 "In3.Cu" signal "L4VCC")
		(10 "In4.Cu" signal "L5VCC")
		(12 "In5.Cu" signal "L6")
		(14 "In6.Cu" signal "L7GND")
		(2 "B.Cu" signal "BOTTOM")
		(9 "F.Adhes" user "F.Adhesive")
		(11 "B.Adhes" user "B.Adhesive")
		(13 "F.Paste" user "Package Geometry/Pastemask Top")
		(15 "B.Paste" user "Package Geometry/Pastemask Bottom")
		(5 "F.SilkS" user "Ref Des/Silkscreen Top")
		(7 "B.SilkS" user "Ref Des/Silkscreen Bottom")
		(1 "F.Mask" user "Board Geometry/Soldermask Top")
		(3 "B.Mask" user "Board Geometry/Soldermask Bottom")
		(17 "Dwgs.User" user "User.Drawings")
		(19 "Cmts.User" user "User.Comments")
		(21 "Eco1.User" user "User.Eco1")
		(23 "Eco2.User" user "User.Eco2")
		(25 "Edge.Cuts" user "Board Geometry/Outline")
		(27 "Margin" user)
		(31 "F.CrtYd" user "Package Geometry/Place Bound Top")
		(29 "B.CrtYd" user "Package Geometry/Place Bound Bottom")
		(35 "F.Fab" user "Ref Des/Assembly Top")
		(33 "B.Fab" user "Ref Des/Assembly Bottom")
	)
	(footprint ""
		(layer "F.Cu")
		(at 28.200096 -258.910074 -90)
		(property "Reference" "HDDSAS0"
			(at 0 0 270)
			(layer "F.SilkS")
			(hide yes)
			(effects
				(font
					(size 1.27 1.27)
				)
			)
		)
		(property "Value" "SKT-SAS15P-14P-45-GP"
			(at -20.7645 -8.9789 270)
			(unlocked yes)
			(layer "F.Fab")
			(hide yes)
			(effects
				(font
					(size 1.016 1.016)
					(thickness 0.1524)
				)
			)
		)
		(property "Device Type" "10120818-001C-TRLF"
			(at -20.7645 -10.5029 270)
			(unlocked yes)
			(layer "F.Fab")
			(hide yes)
			(effects
				(font
					(size 1.016 1.016)
					(thickness 0.1524)
				)
			)
		)
		(duplicate_pad_numbers_are_jumpers no)
		(fp_line
			(start 1.651 4.2926)
			(end 1.651 3.0099)
			(stroke
				(width 0.1524)
				(type default)
			)
			(layer "F.SilkS")
		)
		(fp_line
			(start 8.509 4.2926)
			(end 1.651 4.2926)
			(stroke
				(width 0.1524)
				(type default)
			)
			(layer "F.SilkS")
		)
		(fp_line
			(start -23.4188 3.0099)
			(end -23.4188 -3.2512)
			(stroke
				(width 0.1524)
				(type default)
			)
			(layer "F.SilkS")
		)
		(fp_line
			(start 1.651 3.0099)
			(end -23.4188 3.0099)
			(stroke
				(width 0.1524)
				(type default)
			)
			(layer "F.SilkS")
		)
		(fp_line
			(start 8.509 3.0099)
			(end 8.509 4.2926)
			(stroke
				(width 0.1524)
				(type default)
			)
			(layer "F.SilkS")
		)
		(fp_line
			(start 23.4188 3.0099)
			(end 8.509 3.0099)
			(stroke
				(width 0.1524)
				(type default)
			)
			(layer "F.SilkS")
		)
		(fp_line
			(start -23.4188 -3.2512)
			(end 23.4188 -3.2512)
			(stroke
				(width 0.1524)
				(type default)
			)
			(layer "F.SilkS")
		)
		(fp_line
			(start 23.4188 -3.2512)
			(end 23.4188 3.0099)
			(stroke
				(width 0.1524)
				(type default)
			)
			(layer "F.SilkS")
		)
		(fp_line
			(start 15.5067 -3.3401)
			(end 16.2687 -3.3401)
			(stroke
				(width 0.3302)
				(type default)
			)
			(layer "F.SilkS")
		)
		(fp_poly
			(pts
				(xy 15.868904 -3.230372) (xy 16.503904 -3.865372) (xy 15.233904 -3.865372)
			)
			(stroke
				(width 0)
				(type default)
			)
			(fill yes)
			(layer "F.SilkS")
		)
		(fp_poly
			(pts
				(xy -22.8727 -2.7559) (xy 22.8727 -2.7559) (xy 22.8727 2.7559) (xy 8.255 2.7559) (xy 8.255 3.5179)
				(xy 1.905 3.5179) (xy 1.905 2.7559) (xy -22.8727 2.7559)
			)
			(stroke
				(width 0)
				(type default)
			)
			(fill no)
			(layer "F.CrtYd")
		)
		(fp_poly
			(pts
				(xy 1.397 4.5466) (xy 1.397 3.2639) (xy -23.6728 3.2639) (xy -23.6728 -3.5052) (xy 23.6728 -3.5052)
				(xy 23.6728 -0.00635) (xy 22.8727 -0.00635) (xy 22.8727 -2.7559) (xy -22.8727 -2.7559) (xy -22.8727 2.7559)
				(xy 1.905 2.7559) (xy 1.905 3.5179) (xy 8.255 3.5179) (xy 8.255 2.7559) (xy 22.8727 2.7559) (xy 22.8727 0.00635)
				(xy 23.6728 0.00635) (xy 23.6728 3.2639) (xy 8.763 3.2639) (xy 8.763 4.5466)
			)
			(stroke
				(width 0)
				(type default)
			)
			(fill no)
			(layer "F.CrtYd")
		)
		(fp_poly
			(pts
				(xy 1.397 4.5466) (xy 1.397 3.2639) (xy -23.6728 3.2639) (xy -23.6728 -3.5052) (xy 23.6728 -3.5052)
				(xy 23.6728 3.2639) (xy 8.763 3.2639) (xy 8.763 4.5466)
			)
			(stroke
				(width 0)
				(type default)
			)
			(fill no)
			(layer "F.Fab")
		)
		(pad "" np_thru_hole circle
			(at -18.874994 0 270)
			(size 0.254 0.254)
			(drill 1.3462)
			(layers "*.Cu" "*.Mask")
			(clearance 0.9017)
			(thermal_gap 0.9017)
		)
		(pad "" np_thru_hole circle
			(at 18.874994 0 270)
			(size 0.254 0.254)
			(drill 0.9398)
			(layers "*.Cu" "*.Mask")
			(clearance 0.6985)
			(thermal_gap 0.6985)
		)
		(pad "G1" smd rect
			(at 21.874988 0 270)
			(size 2.5908 2.5908)
			(layers "F.Cu" "F.Mask" "F.Paste")
			(net "GND")
		)
		(pad "G2" smd rect
			(at -21.874988 0 270)
			(size 2.5908 2.5908)
			(layers "F.Cu" "F.Mask" "F.Paste")
			(net "GND")
		)
		(pad "P1" smd rect
			(at 1.905 -1.82499 270)
			(size 0.6096 2.3622)
			(layers "F.Cu" "F.Mask" "F.Paste")
			(net "Net_1764")
		)
		(pad "P2" smd rect
			(at 0.635 -1.82499 270)
			(size 0.6096 2.3622)
			(layers "F.Cu" "F.Mask" "F.Paste")
			(net "Net_1765")
		)
		(pad "P3" smd rect
			(at -0.635 -1.82499 270)
			(size 0.6096 2.3622)
			(layers "F.Cu" "F.Mask" "F.Paste")
			(net "Net_1766")
		)
		(pad "P4" smd rect
			(at -1.905 -1.82499 270)
			(size 0.6096 2.3622)
			(layers "F.Cu" "F.Mask" "F.Paste")
			(net "GND")
		)
		(pad "P5" smd rect
			(at -3.175 -1.82499 270)
			(size 0.6096 2.3622)
			(layers "F.Cu" "F.Mask" "F.Paste")
			(net "HDD_PRSNT_0")
		)
		(pad "P6" smd rect
			(at -4.445 -1.82499 270)
			(size 0.6096 2.3622)
			(layers "F.Cu" "F.Mask" "F.Paste")
			(net "GND")
		)
		(pad "P7" smd rect
			(at -5.715 -1.82499 270)
			(size 0.6096 2.3622)
			(layers "F.Cu" "F.Mask" "F.Paste")
			(net "5V_PRE_0")
		)
		(pad "P8" smd rect
			(at -6.985 -1.82499 270)
			(size 0.6096 2.3622)
			(layers "F.Cu" "F.Mask" "F.Paste")
			(net "P5V_HDD0")
		)
		(pad "P9" smd rect
			(at -8.255 -1.82499 270)
			(size 0.6096 2.3622)
			(layers "F.Cu" "F.Mask" "F.Paste")
			(net "P5V_HDD0")
		)
		(pad "P10" smd rect
			(at -9.525 -1.82499 270)
			(size 0.6096 2.3622)
			(layers "F.Cu" "F.Mask" "F.Paste")
			(net "GND")
		)
		(pad "P11" smd rect
			(at -10.795 -1.82499 270)
			(size 0.6096 2.3622)
			(layers "F.Cu" "F.Mask" "F.Paste")
			(net "ACT_HDD_0")
		)
		(pad "P12" smd rect
			(at -12.065 -1.82499 270)
			(size 0.6096 2.3622)
			(layers "F.Cu" "F.Mask" "F.Paste")
			(net "GND")
		)
		(pad "P13" smd rect
			(at -13.335 -1.82499 270)
			(size 0.6096 2.3622)
			(layers "F.Cu" "F.Mask" "F.Paste")
			(net "12V_PRE_0")
		)
		(pad "P14" smd rect
			(at -14.605 -1.82499 270)
			(size 0.6096 2.3622)
			(layers "F.Cu" "F.Mask" "F.Paste")
			(net "P12V_HDD0")
		)
		(pad "P15" smd rect
			(at -15.875 -1.82499 270)
			(size 0.6096 2.3622)
			(layers "F.Cu" "F.Mask" "F.Paste")
			(net "P12V_HDD0")
		)
		(pad "S1" smd rect
			(at 15.875 -1.82499 270)
			(size 0.6096 2.3622)
			(layers "F.Cu" "F.Mask" "F.Paste")
			(net "GND")
		)
		(pad "S2" smd rect
			(at 14.605 -1.82499 270)
			(size 0.6096 2.3622)
			(layers "F.Cu" "F.Mask" "F.Paste")
			(net "SAS_HDD_RX_P0")
		)
		(pad "S3" smd rect
			(at 13.335 -1.82499 270)
			(size 0.6096 2.3622)
			(layers "F.Cu" "F.Mask" "F.Paste")
			(net "SAS_HDD_RX_N0")
		)
		(pad "S4" smd rect
			(at 12.065 -1.82499 270)
			(size 0.6096 2.3622)
			(layers "F.Cu" "F.Mask" "F.Paste")
			(net "GND")
		)
		(pad "S5" smd rect
			(at 10.795 -1.82499 270)
			(size 0.6096 2.3622)
			(layers "F.Cu" "F.Mask" "F.Paste")
			(net "PHY_DRV_B_TO_SCC_B_0_DN")
		)
		(pad "S6" smd rect
			(at 9.525 -1.82499 270)
			(size 0.6096 2.3622)
			(layers "F.Cu" "F.Mask" "F.Paste")
			(net "PHY_DRV_B_TO_SCC_B_0_DP")
		)
		(pad "S7" smd rect
			(at 8.255 -1.82499 270)
			(size 0.6096 2.3622)
			(layers "F.Cu" "F.Mask" "F.Paste")
			(net "GND")
		)
		(pad "S8" smd rect
			(at 7.480046 2.845054 270)
			(size 0.508 2.3622)
			(layers "F.Cu" "F.Mask" "F.Paste")
			(net "GND")
		)
		(pad "S9" smd rect
			(at 6.679946 2.845054 270)
			(size 0.508 2.3622)
			(layers "F.Cu" "F.Mask" "F.Paste")
			(net "Net_431")
		)
		(pad "S10" smd rect
			(at 5.8801 2.845054 270)
			(size 0.508 2.3622)
			(layers "F.Cu" "F.Mask" "F.Paste")
			(net "Net_323")
		)
		(pad "S11" smd rect
			(at 5.08 2.845054 270)
			(size 0.508 2.3622)
			(layers "F.Cu" "F.Mask" "F.Paste")
			(net "GND")
		)
		(pad "S12" smd rect
			(at 4.2799 2.845054 270)
			(size 0.508 2.3622)
			(layers "F.Cu" "F.Mask" "F.Paste")
			(net "Net_359")
		)
		(pad "S13" smd rect
			(at 3.480054 2.845054 270)
			(size 0.508 2.3622)
			(layers "F.Cu" "F.Mask" "F.Paste")
			(net "Net_395")
		)
		(pad "S14" smd rect
			(at 2.679954 2.845054 270)
			(size 0.508 2.3622)
			(layers "F.Cu" "F.Mask" "F.Paste")
			(net "GND")
		)
		(zone
			(layer "F.Cu")
			(hatch none 0.5)
			(connect_pads
				(clearance 0)
			)
			(min_thickness 0.25)
			(keepout
				(tracks not_allowed)
				(vias allowed)
				(pads allowed)
				(copperpour not_allowed)
				(footprints allowed)
			)
			(placement
				(enabled no)
				(sheetname "")
			)
			(fill
				(thermal_gap 0.5)
				(thermal_bridge_width 0.5)
				(island_removal_mode 0)
			)
			(polygon
				(pts
					(xy 31.857696 -275.648674) (xy 24.783796 -275.648674) (xy 24.783796 -282.582874) (xy 25.888696 -282.582874)
					(xy 25.888696 -278.468074) (xy 30.511496 -278.468074) (xy 30.511496 -282.582874) (xy 31.857696 -282.582874)
				)
			)
		)
		(zone
			(layer "F.Cu")
			(hatch none 0.5)
			(connect_pads
				(clearance 0)
			)
			(min_thickness 0.25)
			(keepout
				(tracks allowed)
				(vias not_allowed)
				(pads allowed)
				(copperpour not_allowed)
				(footprints allowed)
			)
			(placement
				(enabled no)
				(sheetname "")
			)
			(fill
				(thermal_gap 0.5)
				(thermal_bridge_width 0.5)
				(island_removal_mode 0)
			)
			(polygon
				(pts
					(xy 31.857696 -275.648674) (xy 24.783796 -275.648674) (xy 24.783796 -282.582874) (xy 25.888696 -282.582874)
					(xy 25.888696 -278.468074) (xy 30.511496 -278.468074) (xy 30.511496 -282.582874) (xy 31.857696 -282.582874)
				)
			)
		)
		(zone
			(layer "F.Cu")
			(hatch none 0.5)
			(connect_pads
				(clearance 0)
			)
			(min_thickness 0.25)
			(keepout
				(tracks allowed)
				(vias not_allowed)
				(pads allowed)
				(copperpour not_allowed)
				(footprints allowed)
			)
			(placement
				(enabled no)
				(sheetname "")
			)
			(fill
				(thermal_gap 0.5)
				(thermal_bridge_width 0.5)
				(island_removal_mode 0)
			)
			(polygon
				(pts
					(xy 31.857696 -242.171474) (xy 24.783796 -242.171474) (xy 24.783796 -235.237274) (xy 25.888696 -235.237274)
					(xy 25.888696 -239.352074) (xy 30.511496 -239.352074) (xy 30.511496 -235.237274) (xy 31.857696 -235.237274)
				)
			)
		)
		(zone
			(layer "F.Cu")
			(hatch none 0.5)
			(connect_pads
				(clearance 0)
			)
			(min_thickness 0.25)
			(keepout
				(tracks not_allowed)
				(vias allowed)
				(pads allowed)
				(copperpour not_allowed)
				(footprints allowed)
			)
			(placement
				(enabled no)
				(sheetname "")
			)
			(fill
				(thermal_gap 0.5)
				(thermal_bridge_width 0.5)
				(island_removal_mode 0)
			)
			(polygon
				(pts
					(xy 31.857696 -242.171474) (xy 24.783796 -242.171474) (xy 24.783796 -235.237274) (xy 25.888696 -235.237274)
					(xy 25.888696 -239.352074) (xy 30.511496 -239.352074) (xy 30.511496 -235.237274) (xy 31.857696 -235.237274)
				)
			)
		)
		(zone
			(layers "F.Cu" "B.Cu" "In1.Cu" "In2.Cu" "In3.Cu" "In4.Cu" "In5.Cu" "In6.Cu")
			(hatch none 0.5)
			(connect_pads
				(clearance 0)
			)
			(min_thickness 0.25)
			(keepout
				(tracks not_allowed)
				(vias allowed)
				(pads allowed)
				(copperpour not_allowed)
				(footprints allowed)
			)
			(placement
				(enabled no)
				(sheetname "")
			)
			(fill
				(thermal_gap 0.5)
				(thermal_bridge_width 0.5)
				(island_removal_mode 0)
			)
			(polygon
				(pts
					(arc
						(start 28.974796 -240.03508)
						(mid 27.425396 -240.03508)
						(end 28.974796 -240.03508)
					)
				)
			)
		)
		(zone
			(layers "F.Cu" "B.Cu" "In1.Cu" "In2.Cu" "In3.Cu" "In4.Cu" "In5.Cu" "In6.Cu")
			(hatch none 0.5)
			(connect_pads
				(clearance 0)
			)
			(min_thickness 0.25)
			(keepout
				(tracks not_allowed)
				(vias allowed)
				(pads allowed)
				(copperpour not_allowed)
				(footprints allowed)
			)
			(placement
				(enabled no)
				(sheetname "")
			)
			(fill
				(thermal_gap 0.5)
				(thermal_bridge_width 0.5)
				(island_removal_mode 0)
			)
			(polygon
				(pts
					(arc
						(start 29.177996 -277.785068)
						(mid 27.222196 -277.785068)
						(end 29.177996 -277.785068)
					)
				)
			)
		)
	)
	(footprint ""
		(layer "F.Cu")
		(at 146.939 -256.286 180)
		(property "Reference" "Q14"
			(at 0 0 180)
			(layer "F.SilkS")
			(hide yes)
			(effects
				(font
					(size 1.27 1.27)
				)
			)
		)
		(property "Value" "AO4406AL-GP"
			(at -3.707384 -1.5367 180)
			(unlocked yes)
			(layer "F.Fab")
			(hide yes)
			(effects
				(font
					(size 1.016 1.016)
					(thickness 0.1524)
				)
			)
		)
		(property "Device Type" "SOIC8H69"
			(at -3.707384 -3.0607 180)
			(unlocked yes)
			(layer "F.Fab")
			(hide yes)
			(effects
				(font
					(size 1.016 1.016)
					(thickness 0.1524)
				)
			)
		)
		(duplicate_pad_numbers_are_jumpers no)
		(fp_line
			(start 2.1336 1.4224)
			(end 2.1336 -1.4224)
			(stroke
				(width 0.1524)
				(type default)
			)
			(layer "F.SilkS")
		)
		(fp_line
			(start 2.1336 -1.4224)
			(end -2.7432 -1.4224)
			(stroke
				(width 0.1524)
				(type default)
			)
			(layer "F.SilkS")
		)
		(fp_line
			(start -2.1844 -0.0508)
			(end -2.7178 0.508)
			(stroke
				(width 0.1524)
				(type default)
			)
			(layer "F.SilkS")
		)
		(fp_line
			(start -2.6289 3.4417)
			(end -2.6289 1.4732)
			(stroke
				(width 0.381)
				(type default)
			)
			(layer "F.SilkS")
		)
		(fp_line
			(start -2.7178 -0.508)
			(end -2.1844 -0.0508)
			(stroke
				(width 0.1524)
				(type default)
			)
			(layer "F.SilkS")
		)
		(fp_line
			(start -2.7432 1.4224)
			(end 2.1336 1.4224)
			(stroke
				(width 0.1524)
				(type default)
			)
			(layer "F.SilkS")
		)
		(fp_line
			(start -2.7432 1.4224)
			(end -2.6416 1.4224)
			(stroke
				(width 0.1524)
				(type default)
			)
			(layer "F.SilkS")
		)
		(fp_line
			(start -2.7432 -1.4224)
			(end -2.7432 1.4224)
			(stroke
				(width 0.1524)
				(type default)
			)
			(layer "F.SilkS")
		)
		(fp_poly
			(pts
				(xy -2.2098 -1.4224) (xy -2.2098 1.4224) (xy 2.2098 1.4224) (xy 2.2098 -1.4224)
			)
			(stroke
				(width 0)
				(type default)
			)
			(fill yes)
			(layer "F.SilkS")
		)
		(fp_rect
			(start -2.450084 2.999994)
			(end 2.450084 -2.999994)
			(stroke
				(width 0)
				(type default)
			)
			(fill no)
			(layer "F.CrtYd")
		)
		(fp_poly
			(pts
				(xy -2.8194 3.6322) (xy -2.8194 -3.6322) (xy 2.8194 -3.6322) (xy 2.8194 1.18364) (xy 2.450084 1.18364)
				(xy 2.450084 -2.999994) (xy -2.450084 -2.999994) (xy -2.450084 2.999994) (xy 2.450084 2.999994)
				(xy 2.450084 1.18618) (xy 2.8194 1.18618) (xy 2.8194 3.6322)
			)
			(stroke
				(width 0)
				(type default)
			)
			(fill no)
			(layer "F.CrtYd")
		)
		(fp_rect
			(start -2.8194 3.6322)
			(end 2.8194 -3.6322)
			(stroke
				(width 0)
				(type default)
			)
			(fill no)
			(layer "F.Fab")
		)
		(pad "1" smd rect
			(at -1.905 2.54 180)
			(size 0.635 1.651)
			(layers "F.Cu" "F.Mask" "F.Paste")
			(net "P5V_HDD4")
		)
		(pad "2" smd rect
			(at -0.635 2.54 180)
			(size 0.635 1.651)
			(layers "F.Cu" "F.Mask" "F.Paste")
			(net "P5V_HDD4")
		)
		(pad "3" smd rect
			(at 0.635 2.54 180)
			(size 0.635 1.651)
			(layers "F.Cu" "F.Mask" "F.Paste")
			(net "P5V_HDD4")
		)
		(pad "4" smd rect
			(at 1.905 2.54 180)
			(size 0.635 1.651)
			(layers "F.Cu" "F.Mask" "F.Paste")
			(net "SW_HDD_P4")
		)
		(pad "5" smd rect
			(at 1.905 -2.54 180)
			(size 0.635 1.651)
			(layers "F.Cu" "F.Mask" "F.Paste")
			(net "P5V_B_1")
		)
		(pad "6" smd rect
			(at 0.635 -2.54 180)
			(size 0.635 1.651)
			(layers "F.Cu" "F.Mask" "F.Paste")
			(net "P5V_B_1")
		)
		(pad "7" smd rect
			(at -0.635 -2.54 180)
			(size 0.635 1.651)
			(layers "F.Cu" "F.Mask" "F.Paste")
			(net "P5V_B_1")
		)
		(pad "8" smd rect
			(at -1.905 -2.54 180)
			(size 0.635 1.651)
			(layers "F.Cu" "F.Mask" "F.Paste")
			(net "P5V_B_1")
		)
	)
	(footprint ""
		(layer "F.Cu")
		(at 320.34353 -97.350326 -90)
		(property "Reference" "R467"
			(at 0 0 270)
			(layer "F.SilkS")
			(hide yes)
			(effects
				(font
					(size 1.27 1.27)
				)
			)
		)
		(property "Value" "4K7R2F-GP"
			(at 0.064008 -3.993896 270)
			(unlocked yes)
			(layer "F.Fab")
			(hide yes)
			(effects
				(font
					(size 1.016 1.016)
					(thickness 0.1524)
				)
			)
		)
		(property "Device Type" "R402H16"
			(at 0.064008 -5.517896 270)
			(unlocked yes)
			(layer "F.Fab")
			(hide yes)
			(effects
				(font
					(size 1.016 1.016)
					(thickness 0.1524)
				)
			)
		)
		(duplicate_pad_numbers_are_jumpers no)
		(fp_line
			(start -0.508 -0.9398)
			(end -0.508 0.9398)
			(stroke
				(width 0.1524)
				(type default)
			)
			(layer "F.SilkS")
		)
		(fp_line
			(start 0.508 -0.9398)
			(end -0.508 -0.9398)
			(stroke
				(width 0.1524)
				(type default)
			)
			(layer "F.SilkS")
		)
		(fp_rect
			(start -0.508 0.9398)
			(end 0.508 -0.9398)
			(stroke
				(width 0)
				(type default)
			)
			(fill no)
			(layer "F.CrtYd")
		)
		(fp_rect
			(start -0.508 0.9398)
			(end 0.508 -0.9398)
			(stroke
				(width 0)
				(type default)
			)
			(fill no)
			(layer "F.Fab")
		)
		(pad "1" smd custom
			(at 0 -0.4445 270)
			(size 0.1397 0.1397)
			(layers "F.Cu" "F.Mask" "F.Paste")
			(net "DRIVE_B_18_ACT")
			(options
				(clearance outline)
				(anchor circle)
			)
			(primitives
				(gr_poly
					(pts
						(arc
							(start -0.1778 -0.2794)
							(mid -0.249642 -0.249642)
							(end -0.2794 -0.1778)
						)
						(arc
							(start -0.2794 0.1778)
							(mid -0.249642 0.249642)
							(end -0.1778 0.2794)
						)
						(arc
							(start 0.1778 0.2794)
							(mid 0.249642 0.249642)
							(end 0.2794 0.1778)
						)
						(arc
							(start 0.2794 -0.1778)
							(mid 0.249642 -0.249642)
							(end 0.1778 -0.2794)
						)
					)
					(width 0)
					(fill yes)
				)
			)
		)
		(pad "2" smd custom
			(at 0 0.4445 270)
			(size 0.1397 0.1397)
			(layers "F.Cu" "F.Mask" "F.Paste")
			(net "GND")
			(options
				(clearance outline)
				(anchor circle)
			)
			(primitives
				(gr_poly
					(pts
						(arc
							(start -0.1778 -0.2794)
							(mid -0.249642 -0.249642)
							(end -0.2794 -0.1778)
						)
						(arc
							(start -0.2794 0.1778)
							(mid -0.249642 0.249642)
							(end -0.1778 0.2794)
						)
						(arc
							(start 0.1778 0.2794)
							(mid 0.249642 0.249642)
							(end 0.2794 0.1778)
						)
						(arc
							(start 0.2794 -0.1778)
							(mid 0.249642 -0.249642)
							(end 0.1778 -0.2794)
						)
					)
					(width 0)
					(fill yes)
				)
			)
		)
	)
)
